(kicad_pcb
	(version 20260206)
	(generator "pcbnew")
	(generator_version "10.0")
	(general
		(thickness 1.6)
		(legacy_teardrops no)
	)
	(paper "A4")
	(title_block
		(title "04192023_DAF0TMB3IC0_F0TG_MB_C_brd_V02_OCP.brd")
		(comment 1 "Grand Teton / footprints 3606-3612 of 8354")
	)
	(layers
		(0 "F.Cu" signal "TOP")
		(4 "In1.Cu" signal "GND")
		(6 "In2.Cu" signal "IN1")
		(8 "In3.Cu" signal "GND1")
		(10 "In4.Cu" signal "IN2")
		(12 "In5.Cu" signal "GND2")
		(14 "In6.Cu" signal "IN3")
		(16 "In7.Cu" signal "GND3")
		(18 "In8.Cu" signal "VCC")
		(20 "In9.Cu" signal "VCC1")
		(22 "In10.Cu" signal "GND4")
		(24 "In11.Cu" signal "IN4")
		(26 "In12.Cu" signal "GND5")
		(28 "In13.Cu" signal "IN5")
		(30 "In14.Cu" signal "GND6")
		(32 "In15.Cu" signal "IN6")
		(34 "In16.Cu" signal "GND7")
		(2 "B.Cu" signal "BOTTOM")
		(9 "F.Adhes" user "F.Adhesive")
		(11 "B.Adhes" user "B.Adhesive")
		(13 "F.Paste" user "Package Geometry/Pastemask Top")
		(15 "B.Paste" user "Package Geometry/Pastemask Bottom")
		(5 "F.SilkS" user "Ref Des/Silkscreen Top")
		(7 "B.SilkS" user "Ref Des/Silkscreen Bottom")
		(1 "F.Mask" user "Board Geometry/Soldermask Top")
		(3 "B.Mask" user "Board Geometry/Soldermask Bottom")
		(17 "Dwgs.User" user "User.Drawings")
		(19 "Cmts.User" user "User.Comments")
		(21 "Eco1.User" user "User.Eco1")
		(23 "Eco2.User" user "User.Eco2")
		(25 "Edge.Cuts" user "Board Geometry/Outline")
		(27 "Margin" user)
		(31 "F.CrtYd" user "Package Geometry/Place Bound Top")
		(29 "B.CrtYd" user "Package Geometry/Place Bound Bottom")
		(35 "F.Fab" user "Ref Des/Assembly Top")
		(33 "B.Fab" user "Ref Des/Assembly Bottom")
	)
	(footprint ""
		(layer "F.Cu")
		(at 70.052438 -31.887922 -90)
		(property "Reference" "R3630"
			(at 0 0 270)
			(layer "F.SilkS")
			(hide yes)
			(effects
				(font
					(size 1.27 1.27)
				)
			)
		)
		(property "Value" ""
			(at 0 0 270)
			(layer "F.Fab")
			(effects
				(font
					(size 1.27 1.27)
				)
			)
		)
		(duplicate_pad_numbers_are_jumpers no)
		(fp_line
			(start -0.7874 0.4064)
			(end -0.7874 -0.4064)
			(stroke
				(width 0.1524)
				(type default)
			)
			(layer "F.SilkS")
		)
		(fp_line
			(start 0.7874 0.4064)
			(end -0.7874 0.4064)
			(stroke
				(width 0.1524)
				(type default)
			)
			(layer "F.SilkS")
		)
		(fp_line
			(start -0.7874 -0.4064)
			(end 0.7874 -0.4064)
			(stroke
				(width 0.1524)
				(type default)
			)
			(layer "F.SilkS")
		)
		(fp_line
			(start 0.7874 -0.4064)
			(end 0.7874 0.4064)
			(stroke
				(width 0.1524)
				(type default)
			)
			(layer "F.SilkS")
		)
		(fp_line
			(start -0.67945 0.3048)
			(end -0.67945 -0.305054)
			(stroke
				(width 0.1)
				(type default)
			)
			(layer "F.Fab")
		)
		(fp_line
			(start -0.12065 0.3048)
			(end -0.67945 0.3048)
			(stroke
				(width 0.1)
				(type default)
			)
			(layer "F.Fab")
		)
		(fp_line
			(start 0.120396 0.3048)
			(end 0.120396 0.2794)
			(stroke
				(width 0.1)
				(type default)
			)
			(layer "F.Fab")
		)
		(fp_line
			(start 0.67945 0.3048)
			(end 0.120396 0.3048)
			(stroke
				(width 0.1)
				(type default)
			)
			(layer "F.Fab")
		)
		(fp_line
			(start -0.12065 0.2794)
			(end -0.12065 0.3048)
			(stroke
				(width 0.1)
				(type default)
			)
			(layer "F.Fab")
		)
		(fp_line
			(start 0.120396 0.2794)
			(end -0.12065 0.2794)
			(stroke
				(width 0.1)
				(type default)
			)
			(layer "F.Fab")
		)
		(fp_line
			(start -0.12065 -0.2794)
			(end 0.12065 -0.2794)
			(stroke
				(width 0.1)
				(type default)
			)
			(layer "F.Fab")
		)
		(fp_line
			(start 0.12065 -0.2794)
			(end 0.12065 -0.3048)
			(stroke
				(width 0.1)
				(type default)
			)
			(layer "F.Fab")
		)
		(fp_line
			(start 0.12065 -0.3048)
			(end 0.67945 -0.3048)
			(stroke
				(width 0.1)
				(type default)
			)
			(layer "F.Fab")
		)
		(fp_line
			(start 0.67945 -0.3048)
			(end 0.67945 0.3048)
			(stroke
				(width 0.1)
				(type default)
			)
			(layer "F.Fab")
		)
		(fp_line
			(start -0.67945 -0.305054)
			(end -0.12065 -0.305054)
			(stroke
				(width 0.1)
				(type default)
			)
			(layer "F.Fab")
		)
		(fp_line
			(start -0.12065 -0.305054)
			(end -0.12065 -0.2794)
			(stroke
				(width 0.1)
				(type default)
			)
			(layer "F.Fab")
		)
		(pad "1" smd circle
			(at -0.40005 0 270)
			(size 0 0)
			(layers "F.Cu" "F.Mask" "F.Paste")
			(net "P12V_OCP_V3_2_EN_R")
		)
		(pad "2" smd circle
			(at 0.40005 0 270)
			(size 0 0)
			(layers "F.Cu" "F.Mask" "F.Paste")
			(net "P12V_OCP_V3_2_EN_2_R3")
		)
	)
	(footprint ""
		(layer "F.Cu")
		(at 229.603554 -151.752046 180)
		(property "Reference" "C1521"
			(at 0 0 180)
			(layer "F.SilkS")
			(hide yes)
			(effects
				(font
					(size 1.27 1.27)
				)
			)
		)
		(property "Value" ""
			(at 0 0 180)
			(layer "F.Fab")
			(effects
				(font
					(size 1.27 1.27)
				)
			)
		)
		(duplicate_pad_numbers_are_jumpers no)
		(fp_line
			(start 0.7874 0.4064)
			(end -0.7874 0.4064)
			(stroke
				(width 0.1524)
				(type default)
			)
			(layer "F.SilkS")
		)
		(fp_line
			(start 0.7874 -0.4064)
			(end 0.7874 0.4064)
			(stroke
				(width 0.1524)
				(type default)
			)
			(layer "F.SilkS")
		)
		(fp_line
			(start -0.7874 0.4064)
			(end -0.7874 -0.4064)
			(stroke
				(width 0.1524)
				(type default)
			)
			(layer "F.SilkS")
		)
		(fp_line
			(start -0.7874 -0.4064)
			(end 0.7874 -0.4064)
			(stroke
				(width 0.1524)
				(type default)
			)
			(layer "F.SilkS")
		)
		(fp_line
			(start 0.67945 0.3048)
			(end 0.120396 0.3048)
			(stroke
				(width 0.1)
				(type default)
			)
			(layer "F.Fab")
		)
		(fp_line
			(start 0.67945 -0.3048)
			(end 0.67945 0.3048)
			(stroke
				(width 0.1)
				(type default)
			)
			(layer "F.Fab")
		)
		(fp_line
			(start 0.12065 -0.2794)
			(end 0.12065 -0.3048)
			(stroke
				(width 0.1)
				(type default)
			)
			(layer "F.Fab")
		)
		(fp_line
			(start 0.12065 -0.3048)
			(end 0.67945 -0.3048)
			(stroke
				(width 0.1)
				(type default)
			)
			(layer "F.Fab")
		)
		(fp_line
			(start 0.120396 0.3048)
			(end 0.120396 0.2794)
			(stroke
				(width 0.1)
				(type default)
			)
			(layer "F.Fab")
		)
		(fp_line
			(start 0.120396 0.2794)
			(end -0.12065 0.2794)
			(stroke
				(width 0.1)
				(type default)
			)
			(layer "F.Fab")
		)
		(fp_line
			(start -0.12065 0.3048)
			(end -0.67945 0.3048)
			(stroke
				(width 0.1)
				(type default)
			)
			(layer "F.Fab")
		)
		(fp_line
			(start -0.12065 0.2794)
			(end -0.12065 0.3048)
			(stroke
				(width 0.1)
				(type default)
			)
			(layer "F.Fab")
		)
		(fp_line
			(start -0.12065 -0.2794)
			(end 0.12065 -0.2794)
			(stroke
				(width 0.1)
				(type default)
			)
			(layer "F.Fab")
		)
		(fp_line
			(start -0.12065 -0.305054)
			(end -0.12065 -0.2794)
			(stroke
				(width 0.1)
				(type default)
			)
			(layer "F.Fab")
		)
		(fp_line
			(start -0.67945 0.3048)
			(end -0.67945 -0.305054)
			(stroke
				(width 0.1)
				(type default)
			)
			(layer "F.Fab")
		)
		(fp_line
			(start -0.67945 -0.305054)
			(end -0.12065 -0.305054)
			(stroke
				(width 0.1)
				(type default)
			)
			(layer "F.Fab")
		)
		(pad "1" smd circle
			(at -0.40005 0 180)
			(size 0 0)
			(layers "F.Cu" "F.Mask" "F.Paste")
			(net "PVDD18_S5_P0")
		)
		(pad "2" smd circle
			(at 0.40005 0 180)
			(size 0 0)
			(layers "F.Cu" "F.Mask" "F.Paste")
			(net "GND")
		)
	)
	(footprint ""
		(layer "F.Cu")
		(at 83.878166 -143.785844)
		(property "Reference" "C224"
			(at 0 0 0)
			(layer "F.SilkS")
			(hide yes)
			(effects
				(font
					(size 1.27 1.27)
				)
			)
		)
		(property "Value" ""
			(at 0 0 0)
			(layer "F.Fab")
			(effects
				(font
					(size 1.27 1.27)
				)
			)
		)
		(duplicate_pad_numbers_are_jumpers no)
		(fp_line
			(start -0.7874 -0.4064)
			(end 0.7874 -0.4064)
			(stroke
				(width 0.1524)
				(type default)
			)
			(layer "F.SilkS")
		)
		(fp_line
			(start -0.7874 0.4064)
			(end -0.7874 -0.4064)
			(stroke
				(width 0.1524)
				(type default)
			)
			(layer "F.SilkS")
		)
		(fp_line
			(start 0.7874 -0.4064)
			(end 0.7874 0.4064)
			(stroke
				(width 0.1524)
				(type default)
			)
			(layer "F.SilkS")
		)
		(fp_line
			(start 0.7874 0.4064)
			(end -0.7874 0.4064)
			(stroke
				(width 0.1524)
				(type default)
			)
			(layer "F.SilkS")
		)
		(fp_line
			(start -0.67945 -0.305054)
			(end -0.12065 -0.305054)
			(stroke
				(width 0.1)
				(type default)
			)
			(layer "F.Fab")
		)
		(fp_line
			(start -0.67945 0.3048)
			(end -0.67945 -0.305054)
			(stroke
				(width 0.1)
				(type default)
			)
			(layer "F.Fab")
		)
		(fp_line
			(start -0.12065 -0.305054)
			(end -0.12065 -0.2794)
			(stroke
				(width 0.1)
				(type default)
			)
			(layer "F.Fab")
		)
		(fp_line
			(start -0.12065 -0.2794)
			(end 0.12065 -0.2794)
			(stroke
				(width 0.1)
				(type default)
			)
			(layer "F.Fab")
		)
		(fp_line
			(start -0.12065 0.2794)
			(end -0.12065 0.3048)
			(stroke
				(width 0.1)
				(type default)
			)
			(layer "F.Fab")
		)
		(fp_line
			(start -0.12065 0.3048)
			(end -0.67945 0.3048)
			(stroke
				(width 0.1)
				(type default)
			)
			(layer "F.Fab")
		)
		(fp_line
			(start 0.120396 0.2794)
			(end -0.12065 0.2794)
			(stroke
				(width 0.1)
				(type default)
			)
			(layer "F.Fab")
		)
		(fp_line
			(start 0.120396 0.3048)
			(end 0.120396 0.2794)
			(stroke
				(width 0.1)
				(type default)
			)
			(layer "F.Fab")
		)
		(fp_line
			(start 0.12065 -0.3048)
			(end 0.67945 -0.3048)
			(stroke
				(width 0.1)
				(type default)
			)
			(layer "F.Fab")
		)
		(fp_line
			(start 0.12065 -0.2794)
			(end 0.12065 -0.3048)
			(stroke
				(width 0.1)
				(type default)
			)
			(layer "F.Fab")
		)
		(fp_line
			(start 0.67945 -0.3048)
			(end 0.67945 0.3048)
			(stroke
				(width 0.1)
				(type default)
			)
			(layer "F.Fab")
		)
		(fp_line
			(start 0.67945 0.3048)
			(end 0.120396 0.3048)
			(stroke
				(width 0.1)
				(type default)
			)
			(layer "F.Fab")
		)
		(pad "1" smd circle
			(at -0.40005 0)
			(size 0 0)
			(layers "F.Cu" "F.Mask" "F.Paste")
			(net "P1V8_AUX")
		)
		(pad "2" smd circle
			(at 0.40005 0)
			(size 0 0)
			(layers "F.Cu" "F.Mask" "F.Paste")
			(net "GND")
		)
	)
	(footprint ""
		(layer "F.Cu")
		(at 332.250288 -403.285452 90)
		(property "Reference" "R1012"
			(at 0 0 90)
			(layer "F.SilkS")
			(hide yes)
			(effects
				(font
					(size 1.27 1.27)
				)
			)
		)
		(property "Value" ""
			(at 0 0 90)
			(layer "F.Fab")
			(effects
				(font
					(size 1.27 1.27)
				)
			)
		)
		(duplicate_pad_numbers_are_jumpers no)
		(fp_line
			(start 0.32512 -0.175006)
			(end 0.32512 0.175006)
			(stroke
				(width 0.1)
				(type default)
			)
			(layer "F.Fab")
		)
		(fp_line
			(start -0.32512 -0.175006)
			(end 0.32512 -0.175006)
			(stroke
				(width 0.1)
				(type default)
			)
			(layer "F.Fab")
		)
		(fp_line
			(start 0.32512 0.175006)
			(end -0.32512 0.175006)
			(stroke
				(width 0.1)
				(type default)
			)
			(layer "F.Fab")
		)
		(fp_line
			(start -0.32512 0.175006)
			(end -0.32512 -0.175006)
			(stroke
				(width 0.1)
				(type default)
			)
			(layer "F.Fab")
		)
		(pad "1" smd rect
			(at -0.2667 0 90)
			(size 0.3048 0.381)
			(layers "F.Cu" "F.Mask" "F.Paste")
			(net "RST_RT_CPU0_P1_RESET_N")
		)
		(pad "2" smd rect
			(at 0.2667 0 270)
			(size 0.3048 0.381)
			(layers "F.Cu" "F.Mask" "F.Paste")
			(net "RST_RT_CPU0_P1_RESET_R_N")
		)
	)
	(footprint ""
		(layer "F.Cu")
		(at 5.985002 -403.945852 180)
		(property "Reference" ""
			(at 0 0 180)
			(layer "F.SilkS")
			(hide yes)
			(effects
				(font
					(size 1.27 1.27)
				)
			)
		)
		(property "Value" ""
			(at 0 0 180)
			(layer "F.Fab")
			(effects
				(font
					(size 1.27 1.27)
				)
			)
		)
		(duplicate_pad_numbers_are_jumpers no)
		(pad "1" smd circle
			(at 0 0 180)
			(size 0.9906 0.9906)
			(layers "F.Cu" "F.Mask" "F.Paste")
			(net "Net_2240")
		)
		(zone
			(layer "F.Cu")
			(hatch none 0.5)
			(connect_pads
				(clearance 0)
			)
			(min_thickness 0.25)
			(keepout
				(tracks not_allowed)
				(vias allowed)
				(pads allowed)
				(copperpour not_allowed)
				(footprints allowed)
			)
			(placement
				(enabled no)
				(sheetname "")
			)
			(fill
				(thermal_gap 0.5)
				(thermal_bridge_width 0.5)
				(island_removal_mode 0)
			)
			(polygon
				(pts
					(arc
						(start 7.610602 -403.945852)
						(mid 4.359402 -403.945852)
						(end 7.610602 -403.945852)
					)
				)
			)
		)
	)
	(footprint ""
		(layer "F.Cu")
		(at 449.443602 -428.10811)
		(property "Reference" "PC6604"
			(at 0 0 0)
			(layer "F.SilkS")
			(hide yes)
			(effects
				(font
					(size 1.27 1.27)
				)
			)
		)
		(property "Value" ""
			(at 0 0 0)
			(layer "F.Fab")
			(effects
				(font
					(size 1.27 1.27)
				)
			)
		)
		(duplicate_pad_numbers_are_jumpers no)
		(fp_line
			(start -0.7874 -0.4064)
			(end 0.7874 -0.4064)
			(stroke
				(width 0.1524)
				(type default)
			)
			(layer "F.SilkS")
		)
		(fp_line
			(start -0.7874 0.4064)
			(end -0.7874 -0.4064)
			(stroke
				(width 0.1524)
				(type default)
			)
			(layer "F.SilkS")
		)
		(fp_line
			(start 0.7874 -0.4064)
			(end 0.7874 0.4064)
			(stroke
				(width 0.1524)
				(type default)
			)
			(layer "F.SilkS")
		)
		(fp_line
			(start 0.7874 0.4064)
			(end -0.7874 0.4064)
			(stroke
				(width 0.1524)
				(type default)
			)
			(layer "F.SilkS")
		)
		(fp_line
			(start -0.67945 -0.305054)
			(end -0.12065 -0.305054)
			(stroke
				(width 0.1)
				(type default)
			)
			(layer "F.Fab")
		)
		(fp_line
			(start -0.67945 0.3048)
			(end -0.67945 -0.305054)
			(stroke
				(width 0.1)
				(type default)
			)
			(layer "F.Fab")
		)
		(fp_line
			(start -0.12065 -0.305054)
			(end -0.12065 -0.2794)
			(stroke
				(width 0.1)
				(type default)
			)
			(layer "F.Fab")
		)
		(fp_line
			(start -0.12065 -0.2794)
			(end 0.12065 -0.2794)
			(stroke
				(width 0.1)
				(type default)
			)
			(layer "F.Fab")
		)
		(fp_line
			(start -0.12065 0.2794)
			(end -0.12065 0.3048)
			(stroke
				(width 0.1)
				(type default)
			)
			(layer "F.Fab")
		)
		(fp_line
			(start -0.12065 0.3048)
			(end -0.67945 0.3048)
			(stroke
				(width 0.1)
				(type default)
			)
			(layer "F.Fab")
		)
		(fp_line
			(start 0.120396 0.2794)
			(end -0.12065 0.2794)
			(stroke
				(width 0.1)
				(type default)
			)
			(layer "F.Fab")
		)
		(fp_line
			(start 0.120396 0.3048)
			(end 0.120396 0.2794)
			(stroke
				(width 0.1)
				(type default)
			)
			(layer "F.Fab")
		)
		(fp_line
			(start 0.12065 -0.3048)
			(end 0.67945 -0.3048)
			(stroke
				(width 0.1)
				(type default)
			)
			(layer "F.Fab")
		)
		(fp_line
			(start 0.12065 -0.2794)
			(end 0.12065 -0.3048)
			(stroke
				(width 0.1)
				(type default)
			)
			(layer "F.Fab")
		)
		(fp_line
			(start 0.67945 -0.3048)
			(end 0.67945 0.3048)
			(stroke
				(width 0.1)
				(type default)
			)
			(layer "F.Fab")
		)
		(fp_line
			(start 0.67945 0.3048)
			(end 0.120396 0.3048)
			(stroke
				(width 0.1)
				(type default)
			)
			(layer "F.Fab")
		)
		(pad "1" smd circle
			(at -0.40005 0)
			(size 0 0)
			(layers "F.Cu" "F.Mask" "F.Paste")
			(net "P0V9_RETIMER_CPU0_VCC")
		)
		(pad "2" smd circle
			(at 0.40005 0)
			(size 0 0)
			(layers "F.Cu" "F.Mask" "F.Paste")
			(net "GND")
		)
	)
	(footprint ""
		(layer "F.Cu")
		(at 225.171762 -71.192898 90)
		(property "Reference" "R3977"
			(at 0 0 90)
			(layer "F.SilkS")
			(hide yes)
			(effects
				(font
					(size 1.27 1.27)
				)
			)
		)
		(property "Value" ""
			(at 0 0 90)
			(layer "F.Fab")
			(effects
				(font
					(size 1.27 1.27)
				)
			)
		)
		(duplicate_pad_numbers_are_jumpers no)
		(fp_line
			(start 0.7874 -0.4064)
			(end 0.7874 0.4064)
			(stroke
				(width 0.1524)
				(type default)
			)
			(layer "F.SilkS")
		)
		(fp_line
			(start -0.7874 -0.4064)
			(end 0.7874 -0.4064)
			(stroke
				(width 0.1524)
				(type default)
			)
			(layer "F.SilkS")
		)
		(fp_line
			(start 0.7874 0.4064)
			(end -0.7874 0.4064)
			(stroke
				(width 0.1524)
				(type default)
			)
			(layer "F.SilkS")
		)
		(fp_line
			(start -0.7874 0.4064)
			(end -0.7874 -0.4064)
			(stroke
				(width 0.1524)
				(type default)
			)
			(layer "F.SilkS")
		)
		(fp_line
			(start -0.12065 -0.305054)
			(end -0.12065 -0.2794)
			(stroke
				(width 0.1)
				(type default)
			)
			(layer "F.Fab")
		)
		(fp_line
			(start -0.67945 -0.305054)
			(end -0.12065 -0.305054)
			(stroke
				(width 0.1)
				(type default)
			)
			(layer "F.Fab")
		)
		(fp_line
			(start 0.67945 -0.3048)
			(end 0.67945 0.3048)
			(stroke
				(width 0.1)
				(type default)
			)
			(layer "F.Fab")
		)
		(fp_line
			(start 0.12065 -0.3048)
			(end 0.67945 -0.3048)
			(stroke
				(width 0.1)
				(type default)
			)
			(layer "F.Fab")
		)
		(fp_line
			(start 0.12065 -0.2794)
			(end 0.12065 -0.3048)
			(stroke
				(width 0.1)
				(type default)
			)
			(layer "F.Fab")
		)
		(fp_line
			(start -0.12065 -0.2794)
			(end 0.12065 -0.2794)
			(stroke
				(width 0.1)
				(type default)
			)
			(layer "F.Fab")
		)
		(fp_line
			(start 0.120396 0.2794)
			(end -0.12065 0.2794)
			(stroke
				(width 0.1)
				(type default)
			)
			(layer "F.Fab")
		)
		(fp_line
			(start -0.12065 0.2794)
			(end -0.12065 0.3048)
			(stroke
				(width 0.1)
				(type default)
			)
			(layer "F.Fab")
		)
		(fp_line
			(start 0.67945 0.3048)
			(end 0.120396 0.3048)
			(stroke
				(width 0.1)
				(type default)
			)
			(layer "F.Fab")
		)
		(fp_line
			(start 0.120396 0.3048)
			(end 0.120396 0.2794)
			(stroke
				(width 0.1)
				(type default)
			)
			(layer "F.Fab")
		)
		(fp_line
			(start -0.12065 0.3048)
			(end -0.67945 0.3048)
			(stroke
				(width 0.1)
				(type default)
			)
			(layer "F.Fab")
		)
		(fp_line
			(start -0.67945 0.3048)
			(end -0.67945 -0.305054)
			(stroke
				(width 0.1)
				(type default)
			)
			(layer "F.Fab")
		)
		(pad "1" smd circle
			(at -0.40005 0 90)
			(size 0 0)
			(layers "F.Cu" "F.Mask" "F.Paste")
			(net "P3V3_AUX")
		)
		(pad "2" smd circle
			(at 0.40005 0 90)
			(size 0 0)
			(layers "F.Cu" "F.Mask" "F.Paste")
			(net "P3V3_E1S_FAULT_0")
		)
	)
)
